# S9S_MB_2U (Grand Teton) — schematic netlist excerpt (pin names and nets, part order shuffled) for the footprints in the layout excerpt that follows; sources: Cadence DE-HDL packaged netlist, KiCad conversion of 03242023_DA0F0TMBIJ0_F0T_Motherboard_J_brd_V01_OCP.brd

J10  SCONN288_ADR50017P087CC  SCONN288_ADR50017-P087CC IO  pkg DDR288S_1-1VXB  page 91
  VIN_BULK0  = P12V_S3_AUX_CPU0_NVDIMM
  RFU0  = TP_CHE_CPU0_DIMM2_FRU_0
  VIN_MGMT  = P3V3_AUX
  HSCL  = I3C_SPD_DDREFGH_CPU0_LVC1_SCL_1
  HSDA  = I3C_SPD_DDREFGH_CPU0_LVC1_SDA
  VSS0  = GND
  DQ0_A  = M_E_CPU0_SA_DQ<0>
  VSS1  = GND
  DQ1_A  = M_E_CPU0_SA_DQ<1>
  VSS2  = GND
  DQS0_A_T  = M_E_CPU0_SA_DQS_DP<0>
  DQS0_A_C  = M_E_CPU0_SA_DQS_DN<0>
  VSS3  = GND
  DQ4_A  = M_E_CPU0_SA_DQ<4>
  VSS4  = GND
  DQ5_A  = M_E_CPU0_SA_DQ<5>
  VSS5  = GND
  DQ8_A  = M_E_CPU0_SA_DQ<8>
  VSS6  = GND
  DQ9_A  = M_E_CPU0_SA_DQ<9>
  VSS7  = GND
  DQS1_A_T  = M_E_CPU0_SA_DQS_DP<1>
  DQS1_A_C  = M_E_CPU0_SA_DQS_DN<1>
  VSS8  = GND
  DQ12_A  = M_E_CPU0_SA_DQ<12>
  VSS9  = GND
  DQ13_A  = M_E_CPU0_SA_DQ<13>
  VSS10  = GND
  DQ16_A  = M_E_CPU0_SA_DQ<16>
  VSS11  = GND
  DQ17_A  = M_E_CPU0_SA_DQ<17>
  VSS12  = GND
  DQS2_A_T  = M_E_CPU0_SA_DQS_DP<2>
  DQS2_A_C  = M_E_CPU0_SA_DQS_DN<2>
  VSS13  = GND
  DQ20_A  = M_E_CPU0_SA_DQ<20>
  VSS14  = GND
  DQ21_A  = M_E_CPU0_SA_DQ<21>
  VSS15  = GND
  DQ24_A  = M_E_CPU0_SA_DQ<24>
  VSS16  = GND
  DQ25_A  = M_E_CPU0_SA_DQ<25>
  VSS17  = GND
  DQS3_A_T  = M_E_CPU0_SA_DQS_DP<3>
  DQS3_A_C  = M_E_CPU0_SA_DQS_DN<3>
  VSS18  = GND
  DQ28_A  = M_E_CPU0_SA_DQ<28>
  VSS19  = GND
  DQ29_A  = M_E_CPU0_SA_DQ<29>
  VSS20  = GND
  CB0_A  = M_E_CPU0_SA_CB<0>
  VSS21  = GND
  CB1_A  = M_E_CPU0_SA_CB<1>
  VSS22  = GND
  DQS4_A_T  = M_E_CPU0_SA_DQS_DP<4>
  DQS4_A_C  = M_E_CPU0_SA_DQS_DN<4>
  VSS23  = GND
  CB4_A  = M_E_CPU0_SA_CB<4>
  VSS24  = GND
  CB5_A  = M_E_CPU0_SA_CB<5>
  VSS25  = GND
  ALERT_N  = M_E_CPU0_ALERT_N
  VSS26  = GND
  CS0_A_N  = M_E_CPU0_SA_CS_N<2>
  VSS27  = GND
  CA0_A  = M_E_CPU0_SA_CA<0>
  VSS28  = GND
  CA2_A  = M_E_CPU0_SA_CA<2>
  VSS29  = GND
  CA4_A  = M_E_CPU0_SA_CA<4>
  VSS30  = GND
  CA6_A  = M_E_CPU0_SA_CA<6>
  VSS31  = GND
  PAR_A  = M_E_CPU0_SA_PAR
  VSS32  = GND
  CA0_B  = M_E_CPU0_SB_CA<0>
  VSS33  = GND
  CA2_B  = M_E_CPU0_SB_CA<2>
  VSS34  = GND
  CA4_B  = M_E_CPU0_SB_CA<4>
  VSS35  = GND
  CA6_B  = M_E_CPU0_SB_CA<6>
  VSS36  = GND
  CS0_B_N  = M_E_CPU0_SB_CS_N<2>
  VSS37  = GND
  \lbd||rsp_a_n\  = M_E_CPU0_SA_RSP<1>
  \lbs||rsp_b_n\  = M_E_CPU0_SB_RSP<1>
  VSS38  = GND
  CB4_B  = M_E_CPU0_SB_CB<4>
  VSS39  = GND
  CB5_B  = M_E_CPU0_SB_CB<5>
  VSS40  = GND
  \dqs9_b_t||tdqs9_b_t||dbi4_b_n\  = M_E_CPU0_SB_DQS_DP<9>
  \dqs9_b_c||tdqs9_b_c\  = M_E_CPU0_SB_DQS_DN<9>
  VSS41  = GND
  CB0_B  = M_E_CPU0_SB_CB<0>
  VSS42  = GND
  CB1_B  = M_E_CPU0_SB_CB<1>
  VSS43  = GND
  DQ0_B  = M_E_CPU0_SB_DQ<0>
  VSS44  = GND
  DQ1_B  = M_E_CPU0_SB_DQ<1>
  VSS45  = GND
  DQS0_B_T  = M_E_CPU0_SB_DQS_DP<0>
  DQS0_B_C  = M_E_CPU0_SB_DQS_DN<0>
  VSS46  = GND
  DQ4_B  = M_E_CPU0_SB_DQ<4>
  VSS47  = GND
  DQ5_B  = M_E_CPU0_SB_DQ<5>
  VSS48  = GND
  DQ8_B  = M_E_CPU0_SB_DQ<8>
  VSS49  = GND
  DQ9_B  = M_E_CPU0_SB_DQ<9>
  VSS50  = GND
  DQS1_B_T  = M_E_CPU0_SB_DQS_DP<1>
  DQS1_B_C  = M_E_CPU0_SB_DQS_DN<1>
  VSS51  = GND
  DQ12_B  = M_E_CPU0_SB_DQ<12>
  VSS52  = GND
  DQ13_B  = M_E_CPU0_SB_DQ<13>
  VSS53  = GND
  DQ16_B  = M_E_CPU0_SB_DQ<16>
  VSS54  = GND
  DQ17_B  = M_E_CPU0_SB_DQ<17>
  VSS55  = GND
  DQS2_B_T  = M_E_CPU0_SB_DQS_DP<2>
  DQS2_B_C  = M_E_CPU0_SB_DQS_DN<2>
  VSS56  = GND
  DQ20_B  = M_E_CPU0_SB_DQ<20>
  VSS57  = GND
  DQ21_B  = M_E_CPU0_SB_DQ<21>
  VSS58  = GND
  DQ24_B  = M_E_CPU0_SB_DQ<24>
  VSS59  = GND
  DQ25_B  = M_E_CPU0_SB_DQ<25>
  VSS60  = GND
  DQS3_B_T  = M_E_CPU0_SB_DQS_DP<3>
  DQS3_B_C  = M_E_CPU0_SB_DQS_DN<3>
  VSS61  = GND
  DQ28_B  = M_E_CPU0_SB_DQ<28>
  VSS62  = GND
  DQ29_B  = M_E_CPU0_SB_DQ<29>
  VSS63  = GND
  RFU1  = TP_CHE_CPU0_DIMM2_FRU_1
  VIN_BULK1  = P12V_S3_AUX_CPU0_NVDIMM
  VIN_BULK2  = P12V_S3_AUX_CPU0_NVDIMM
  \pwr_good||fail_n\  = PWRGD_CHE_CPU0_DIMM2
  HSA  = PD_CHE_CPU0_DIMM2_SAA
  RFU2  = TP_CHE_CPU0_DIMM2_FRU_2
  RFU3  = TP_CHE_CPU0_DIMM2_FRU_3
  VSS64  = GND
  DQ2_A  = M_E_CPU0_SA_DQ<2>
  VSS65  = GND
  DQ3_A  = M_E_CPU0_SA_DQ<3>
  VSS66  = GND
  \dqs5_a_c||tdqs5_a_c||dqs5_a_t||tdqs5_a_t\  = M_E_CPU0_SA_DQS_DN<5>
  \dqs5_a_t||tdqs5_a_t\  = M_E_CPU0_SA_DQS_DP<5>
  VSS67  = GND
  DQ6_A  = M_E_CPU0_SA_DQ<6>
  VSS68  = GND
  DQ7_A  = M_E_CPU0_SA_DQ<7>
  VSS69  = GND
  DQ10_A  = M_E_CPU0_SA_DQ<10>
  VSS70  = GND
  DQ11_A  = M_E_CPU0_SA_DQ<11>
  VSS71  = GND
  \dqs6_a_c||tdqs6_a_c||dqs6_a_t||tdqs6_a_t\  = M_E_CPU0_SA_DQS_DN<6>
  \dqs6_a_t||tdqs6_a_t\  = M_E_CPU0_SA_DQS_DP<6>
  VSS72  = GND
  DQ14_A  = M_E_CPU0_SA_DQ<14>
  VSS73  = GND
  DQ15_A  = M_E_CPU0_SA_DQ<15>
  VSS74  = GND
  DQ18_A  = M_E_CPU0_SA_DQ<18>
  VSS75  = GND
  DQ19_A  = M_E_CPU0_SA_DQ<19>
  VSS76  = GND
  \dqs7_a_c||tdqs7_a_c\  = M_E_CPU0_SA_DQS_DN<7>
  \dqs7_a_t||tdqs7_a_t\  = M_E_CPU0_SA_DQS_DP<7>
  VSS77  = GND
  DQ22_A  = M_E_CPU0_SA_DQ<22>
  VSS78  = GND
  DQ23_A  = M_E_CPU0_SA_DQ<23>
  VSS79  = GND
  DQ26_A  = M_E_CPU0_SA_DQ<26>
  VSS80  = GND
  DQ27_A  = M_E_CPU0_SA_DQ<27>
  VSS81  = GND
  \dqs8_a_c||tdqs8_a_c\  = M_E_CPU0_SA_DQS_DN<8>
  \dqs8_a_t||tdqs8_a_t\  = M_E_CPU0_SA_DQS_DP<8>
  VSS82  = GND
  DQ30_A  = M_E_CPU0_SA_DQ<30>
  VSS83  = GND
  DQ31_A  = M_E_CPU0_SA_DQ<31>
  VSS84  = GND
  CB2_A  = M_E_CPU0_SA_CB<2>
  VSS85  = GND
  CB3_A  = M_E_CPU0_SA_CB<3>
  VSS86  = GND
  \dqs9_a_c||tdqs9_a_c\  = M_E_CPU0_SA_DQS_DN<9>
  \dqs9_a_t||tdqs9_a_t\  = M_E_CPU0_SA_DQS_DP<9>
  VSS87  = GND
  CB6_A  = M_E_CPU0_SA_CB<6>
  VSS88  = GND
  CB7_A  = M_E_CPU0_SA_CB<7>
  VSS89  = GND
  RESET_N  = RST_M_EF_CPU0_FPGA_N
  VSS90  = GND
  CS1_A_N  = M_E_CPU0_SA_CS_N<3>
  VSS91  = GND
  CA1_A  = M_E_CPU0_SA_CA<1>
  VSS92  = GND
  CA3_A  = M_E_CPU0_SA_CA<3>
  VSS93  = GND
  CA5_A  = M_E_CPU0_SA_CA<5>
  VSS94  = GND
  CK_T  = M_E_CPU0_CLK_DP<1>
  CK_C  = M_E_CPU0_CLK_DN<1>
  VSS95  = GND
  RFU4  = TP_CHE_CPU0_DIMM2_FRU_4
  CA1_B  = M_E_CPU0_SB_CA<1>
  VSS96  = GND
  CA3_B  = M_E_CPU0_SB_CA<3>
  VSS97  = GND
  CA5_B  = M_E_CPU0_SB_CA<5>
  VSS98  = GND
  PAR_B  = M_E_CPU0_SB_PAR
  VSS99  = GND
  CS1_B_N  = M_E_CPU0_SB_CS_N<3>
  VSS100  = GND
  RFU5  = TP_CHE_CPU0_DIMM2_FRU_5
  RFU6  = TP_CHE_CPU0_DIMM2_FRU_6
  VSS101  = GND
  CB6_B  = M_E_CPU0_SB_CB<6>
  VSS102  = GND
  CB7_B  = M_E_CPU0_SB_CB<7>
  VSS103  = GND
  DQS4_B_C  = M_E_CPU0_SB_DQS_DN<4>
  DQS4_B_T  = M_E_CPU0_SB_DQS_DP<4>
  VSS104  = GND
  CB2_B  = M_E_CPU0_SB_CB<2>
  VSS105  = GND
  CB3_B  = M_E_CPU0_SB_CB<3>
  VSS106  = GND
  DQ2_B  = M_E_CPU0_SB_DQ<2>
  VSS107  = GND
  DQ3_B  = M_E_CPU0_SB_DQ<3>
  VSS108  = GND
  \dqs5_b_c||tdqs5_b_c\  = M_E_CPU0_SB_DQS_DN<5>
  \dqs5_b_t||tdqs5_b_t\  = M_E_CPU0_SB_DQS_DP<5>
  VSS109  = GND
  DQ6_B  = M_E_CPU0_SB_DQ<6>
  VSS110  = GND
  DQ7_B  = M_E_CPU0_SB_DQ<7>
  VSS111  = GND
  DQ10_B  = M_E_CPU0_SB_DQ<10>
  VSS112  = GND
  DQ11_B  = M_E_CPU0_SB_DQ<11>
  VSS113  = GND
  \dqs6_b_c||tdqs6_b_c\  = M_E_CPU0_SB_DQS_DN<6>
  \dqs6_b_t||tdqs6_b_t\  = M_E_CPU0_SB_DQS_DP<6>
  VSS114  = GND
  DQ14_B  = M_E_CPU0_SB_DQ<14>
  VSS115  = GND
  DQ15_B  = M_E_CPU0_SB_DQ<15>
  VSS116  = GND
  DQ18_B  = M_E_CPU0_SB_DQ<18>
  VSS117  = GND
  DQ19_B  = M_E_CPU0_SB_DQ<19>
  VSS118  = GND
  \dqs7_b_c||tdqs7_b_c\  = M_E_CPU0_SB_DQS_DN<7>
  \dqs7_b_t||tdqs7_b_t\  = M_E_CPU0_SB_DQS_DP<7>
  VSS119  = GND
  DQ22_B  = M_E_CPU0_SB_DQ<22>
  VSS120  = GND
  DQ23_B  = M_E_CPU0_SB_DQ<23>
  VSS121  = GND
  DQ26_B  = M_E_CPU0_SB_DQ<26>
  VSS122  = GND
  DQ27_B  = M_E_CPU0_SB_DQ<27>
  VSS123  = GND
  \dqs8_b_c||tdqs8_b_c\  = M_E_CPU0_SB_DQS_DN<8>
  \dqs8_b_t||tdqs8_b_t\  = M_E_CPU0_SB_DQS_DP<8>
  VSS124  = GND
  DQ30_B  = M_E_CPU0_SB_DQ<30>
  VSS125  = GND
  DQ31_B  = M_E_CPU0_SB_DQ<31>
  VSS126  = GND
  G1  = GND
  G2  = GND
  G3  = GND

(kicad_pcb
	(version 20260206)
	(generator "pcbnew")
	(generator_version "10.0")
	(general
		(thickness 1.6)
		(legacy_teardrops no)
	)
	(paper "A4")
	(title_block
		(title "03242023_DA0F0TMBIJ0_F0T_Motherboard_J_brd_V01_OCP.brd")
		(comment 1 "Grand Teton / footprint 1607 of 6105 (J10), pads 229-274 of 291")
	)
	(layers
		(0 "F.Cu" signal "TOP")
		(4 "In1.Cu" signal "GND")
		(6 "In2.Cu" signal "IN1")
		(8 "In3.Cu" signal "GND1")
		(10 "In4.Cu" signal "IN2")
		(12 "In5.Cu" signal "GND2")
		(14 "In6.Cu" signal "IN3")
		(16 "In7.Cu" signal "GND3")
		(18 "In8.Cu" signal "VCC")
		(20 "In9.Cu" signal "VCC1")
		(22 "In10.Cu" signal "GND4")
		(24 "In11.Cu" signal "IN4")
		(26 "In12.Cu" signal "GND5")
		(28 "In13.Cu" signal "IN5")
		(30 "In14.Cu" signal "GND6")
		(32 "In15.Cu" signal "IN6")
		(34 "In16.Cu" signal "GND7")
		(2 "B.Cu" signal "BOTTOM")
		(9 "F.Adhes" user "F.Adhesive")
		(11 "B.Adhes" user "B.Adhesive")
		(13 "F.Paste" user "Package Geometry/Pastemask Top")
		(15 "B.Paste" user "Package Geometry/Pastemask Bottom")
		(5 "F.SilkS" user "Ref Des/Silkscreen Top")
		(7 "B.SilkS" user "Ref Des/Silkscreen Bottom")
		(1 "F.Mask" user "Board Geometry/Soldermask Top")
		(3 "B.Mask" user "Board Geometry/Soldermask Bottom")
		(17 "Dwgs.User" user "User.Drawings")
		(19 "Cmts.User" user "User.Comments")
		(21 "Eco1.User" user "User.Eco1")
		(23 "Eco2.User" user "User.Eco2")
		(25 "Edge.Cuts" user "Board Geometry/Outline")
		(27 "Margin" user)
		(31 "F.CrtYd" user "Package Geometry/Place Bound Top")
		(29 "B.CrtYd" user "Package Geometry/Place Bound Bottom")
		(35 "F.Fab" user "Ref Des/Assembly Top")
		(33 "B.Fab" user "Ref Des/Assembly Bottom")
	)
	(footprint ""
		(layer "F.Cu")
		(at 408.803348 -258.091686)
		(property "Reference" "J10"
			(at -3.683 -81.702148 0)
			(unlocked yes)
			(layer "F.SilkS")
			(effects
				(font
					(size 0.7874 0.5842)
					(thickness 0.1524)
				)
				(justify left)
			)
		)
		(property "Value" ""
			(at 0 0 0)
			(layer "F.Fab")
			(effects
				(font
					(size 1.27 1.27)
				)
			)
		)
		(duplicate_pad_numbers_are_jumpers no)
		(pad "229" smd rect
			(at 2.050034 13.17498 270)
			(size 0.519938 1.4986)
			(layers "F.Cu" "F.Mask" "F.Paste")
			(net "M_E_CPU0_SB_CS_N<3>")
		)
		(pad "230" smd rect
			(at 2.050034 14.025118 270)
			(size 0.519938 1.4986)
			(layers "F.Cu" "F.Mask" "F.Paste")
			(net "GND")
		)
		(pad "231" smd rect
			(at 2.050034 14.875002 270)
			(size 0.519938 1.4986)
			(layers "F.Cu" "F.Mask" "F.Paste")
			(net "TP_CHE_CPU0_DIMM2_FRU_5")
		)
		(pad "232" smd rect
			(at 2.050034 15.724886 270)
			(size 0.519938 1.4986)
			(layers "F.Cu" "F.Mask" "F.Paste")
			(net "TP_CHE_CPU0_DIMM2_FRU_6")
		)
		(pad "233" smd rect
			(at 2.050034 16.575024 270)
			(size 0.519938 1.4986)
			(layers "F.Cu" "F.Mask" "F.Paste")
			(net "GND")
		)
		(pad "234" smd rect
			(at 2.050034 17.424908 270)
			(size 0.519938 1.4986)
			(layers "F.Cu" "F.Mask" "F.Paste")
			(net "M_E_CPU0_SB_CB<6>")
		)
		(pad "235" smd rect
			(at 2.050034 18.275046 270)
			(size 0.519938 1.4986)
			(layers "F.Cu" "F.Mask" "F.Paste")
			(net "GND")
		)
		(pad "236" smd rect
			(at 2.050034 19.12493 270)
			(size 0.519938 1.4986)
			(layers "F.Cu" "F.Mask" "F.Paste")
			(net "M_E_CPU0_SB_CB<7>")
		)
		(pad "237" smd rect
			(at 2.050034 19.975068 270)
			(size 0.519938 1.4986)
			(layers "F.Cu" "F.Mask" "F.Paste")
			(net "GND")
		)
		(pad "238" smd rect
			(at 2.050034 20.824952 270)
			(size 0.519938 1.4986)
			(layers "F.Cu" "F.Mask" "F.Paste")
			(net "M_E_CPU0_SB_DQS_DN<4>")
		)
		(pad "239" smd rect
			(at 2.050034 21.67509 270)
			(size 0.519938 1.4986)
			(layers "F.Cu" "F.Mask" "F.Paste")
			(net "M_E_CPU0_SB_DQS_DP<4>")
		)
		(pad "240" smd rect
			(at 2.050034 22.524974 270)
			(size 0.519938 1.4986)
			(layers "F.Cu" "F.Mask" "F.Paste")
			(net "GND")
		)
		(pad "241" smd rect
			(at 2.050034 23.375112 270)
			(size 0.519938 1.4986)
			(layers "F.Cu" "F.Mask" "F.Paste")
			(net "M_E_CPU0_SB_CB<2>")
		)
		(pad "242" smd rect
			(at 2.050034 24.224996 270)
			(size 0.519938 1.4986)
			(layers "F.Cu" "F.Mask" "F.Paste")
			(net "GND")
		)
		(pad "243" smd rect
			(at 2.050034 25.07488 270)
			(size 0.519938 1.4986)
			(layers "F.Cu" "F.Mask" "F.Paste")
			(net "M_E_CPU0_SB_CB<3>")
		)
		(pad "244" smd rect
			(at 2.050034 25.925018 270)
			(size 0.519938 1.4986)
			(layers "F.Cu" "F.Mask" "F.Paste")
			(net "GND")
		)
		(pad "245" smd rect
			(at 2.050034 26.774902 270)
			(size 0.519938 1.4986)
			(layers "F.Cu" "F.Mask" "F.Paste")
			(net "M_E_CPU0_SB_DQ<2>")
		)
		(pad "246" smd rect
			(at 2.050034 27.62504 270)
			(size 0.519938 1.4986)
			(layers "F.Cu" "F.Mask" "F.Paste")
			(net "GND")
		)
		(pad "247" smd rect
			(at 2.050034 28.474924 270)
			(size 0.519938 1.4986)
			(layers "F.Cu" "F.Mask" "F.Paste")
			(net "M_E_CPU0_SB_DQ<3>")
		)
		(pad "248" smd rect
			(at 2.050034 29.325062 270)
			(size 0.519938 1.4986)
			(layers "F.Cu" "F.Mask" "F.Paste")
			(net "GND")
		)
		(pad "249" smd rect
			(at 2.050034 30.174946 270)
			(size 0.519938 1.4986)
			(layers "F.Cu" "F.Mask" "F.Paste")
			(net "M_E_CPU0_SB_DQS_DN<5>")
		)
		(pad "250" smd rect
			(at 2.050034 31.025084 270)
			(size 0.519938 1.4986)
			(layers "F.Cu" "F.Mask" "F.Paste")
			(net "M_E_CPU0_SB_DQS_DP<5>")
		)
		(pad "251" smd rect
			(at 2.050034 31.874968 270)
			(size 0.519938 1.4986)
			(layers "F.Cu" "F.Mask" "F.Paste")
			(net "GND")
		)
		(pad "252" smd rect
			(at 2.050034 32.725106 270)
			(size 0.519938 1.4986)
			(layers "F.Cu" "F.Mask" "F.Paste")
			(net "M_E_CPU0_SB_DQ<6>")
		)
		(pad "253" smd rect
			(at 2.050034 33.57499 270)
			(size 0.519938 1.4986)
			(layers "F.Cu" "F.Mask" "F.Paste")
			(net "GND")
		)
		(pad "254" smd rect
			(at 2.050034 34.425128 270)
			(size 0.519938 1.4986)
			(layers "F.Cu" "F.Mask" "F.Paste")
			(net "M_E_CPU0_SB_DQ<7>")
		)
		(pad "255" smd rect
			(at 2.050034 35.275012 270)
			(size 0.519938 1.4986)
			(layers "F.Cu" "F.Mask" "F.Paste")
			(net "GND")
		)
		(pad "256" smd rect
			(at 2.050034 36.124896 270)
			(size 0.519938 1.4986)
			(layers "F.Cu" "F.Mask" "F.Paste")
			(net "M_E_CPU0_SB_DQ<10>")
		)
		(pad "257" smd rect
			(at 2.050034 36.975034 270)
			(size 0.519938 1.4986)
			(layers "F.Cu" "F.Mask" "F.Paste")
			(net "GND")
		)
		(pad "258" smd rect
			(at 2.050034 37.824918 270)
			(size 0.519938 1.4986)
			(layers "F.Cu" "F.Mask" "F.Paste")
			(net "M_E_CPU0_SB_DQ<11>")
		)
		(pad "259" smd rect
			(at 2.050034 38.675056 270)
			(size 0.519938 1.4986)
			(layers "F.Cu" "F.Mask" "F.Paste")
			(net "GND")
		)
		(pad "260" smd rect
			(at 2.050034 39.52494 270)
			(size 0.519938 1.4986)
			(layers "F.Cu" "F.Mask" "F.Paste")
			(net "M_E_CPU0_SB_DQS_DN<6>")
		)
		(pad "261" smd rect
			(at 2.050034 40.375078 270)
			(size 0.519938 1.4986)
			(layers "F.Cu" "F.Mask" "F.Paste")
			(net "M_E_CPU0_SB_DQS_DP<6>")
		)
		(pad "262" smd rect
			(at 2.050034 41.224962 270)
			(size 0.519938 1.4986)
			(layers "F.Cu" "F.Mask" "F.Paste")
			(net "GND")
		)
		(pad "263" smd rect
			(at 2.050034 42.0751 270)
			(size 0.519938 1.4986)
			(layers "F.Cu" "F.Mask" "F.Paste")
			(net "M_E_CPU0_SB_DQ<14>")
		)
		(pad "264" smd rect
			(at 2.050034 42.924984 270)
			(size 0.519938 1.4986)
			(layers "F.Cu" "F.Mask" "F.Paste")
			(net "GND")
		)
		(pad "265" smd rect
			(at 2.050034 43.775122 270)
			(size 0.519938 1.4986)
			(layers "F.Cu" "F.Mask" "F.Paste")
			(net "M_E_CPU0_SB_DQ<15>")
		)
		(pad "266" smd rect
			(at 2.050034 44.625006 270)
			(size 0.519938 1.4986)
			(layers "F.Cu" "F.Mask" "F.Paste")
			(net "GND")
		)
		(pad "267" smd rect
			(at 2.050034 45.47489 270)
			(size 0.519938 1.4986)
			(layers "F.Cu" "F.Mask" "F.Paste")
			(net "M_E_CPU0_SB_DQ<18>")
		)
		(pad "268" smd rect
			(at 2.050034 46.325028 270)
			(size 0.519938 1.4986)
			(layers "F.Cu" "F.Mask" "F.Paste")
			(net "GND")
		)
		(pad "269" smd rect
			(at 2.050034 47.174912 270)
			(size 0.519938 1.4986)
			(layers "F.Cu" "F.Mask" "F.Paste")
			(net "M_E_CPU0_SB_DQ<19>")
		)
		(pad "270" smd rect
			(at 2.050034 48.02505 270)
			(size 0.519938 1.4986)
			(layers "F.Cu" "F.Mask" "F.Paste")
			(net "GND")
		)
		(pad "271" smd rect
			(at 2.050034 48.874934 270)
			(size 0.519938 1.4986)
			(layers "F.Cu" "F.Mask" "F.Paste")
			(net "M_E_CPU0_SB_DQS_DN<7>")
		)
		(pad "272" smd rect
			(at 2.050034 49.725072 270)
			(size 0.519938 1.4986)
			(layers "F.Cu" "F.Mask" "F.Paste")
			(net "M_E_CPU0_SB_DQS_DP<7>")
		)
		(pad "273" smd rect
			(at 2.050034 50.574956 270)
			(size 0.519938 1.4986)
			(layers "F.Cu" "F.Mask" "F.Paste")
			(net "GND")
		)
		(pad "274" smd rect
			(at 2.050034 51.425094 270)
			(size 0.519938 1.4986)
			(layers "F.Cu" "F.Mask" "F.Paste")
			(net "M_E_CPU0_SB_DQ<22>")
		)
	)
)
